(kicad_pcb
	(version 20241229)
	(generator "pcbnew")
	(generator_version "9.0")
	(general
		(thickness 1.599998)
		(legacy_teardrops no)
	)
	(paper "A4")
	(title_block
		(title "Artix - Datacenter Secure Control Module (DC-SCM)")
		(date "2024-11-06")
		(rev "1.1.3")
		(comment 9 "footprints 517-521 of 544")
	)
	(layers
		(0 "F.Cu" signal)
		(4 "In1.Cu" signal)
		(6 "In2.Cu" signal)
		(8 "In3.Cu" signal)
		(10 "In4.Cu" signal)
		(12 "In5.Cu" signal)
		(14 "In6.Cu" signal)
		(2 "B.Cu" signal)
		(9 "F.Adhes" user "F.Adhesive")
		(11 "B.Adhes" user "B.Adhesive")
		(13 "F.Paste" user)
		(15 "B.Paste" user)
		(5 "F.SilkS" user "F.Silkscreen")
		(7 "B.SilkS" user "B.Silkscreen")
		(1 "F.Mask" user)
		(3 "B.Mask" user)
		(17 "Dwgs.User" user "User.Drawings")
		(19 "Cmts.User" user "User.Comments")
		(21 "Eco1.User" user "User.Eco1")
		(23 "Eco2.User" user "User.Eco2")
		(25 "Edge.Cuts" user)
		(27 "Margin" user)
		(31 "F.CrtYd" user "F.Courtyard")
		(29 "B.CrtYd" user "B.Courtyard")
		(35 "F.Fab" user)
		(33 "B.Fab" user)
	)
	(footprint "antmicro-footprints:C_0402_1005Metric"
		(layer "B.Cu")
		(at 122.865 113.465 -90)
		(descr "Capacitor SMD 0402")
		(tags "capacitor SMD 0402")
		(property "Reference" "C247"
			(at 0.825 -0.31375 90)
			(layer "B.SilkS")
			(effects
				(font
					(size 0.7 0.7)
					(thickness 0.15)
				)
				(justify left bottom mirror)
			)
		)
		(property "Value" "C_4u7_0402"
			(at 0 -1.4 90)
			(layer "B.Fab")
			(effects
				(font
					(size 0.7 0.7)
					(thickness 0.15)
				)
				(justify left bottom mirror)
			)
		)
		(property "Datasheet" "https://www.murata.com/products/productdetail?partno=GRM155R61A475MEAA%23"
			(at 0 0 270)
			(layer "F.Fab")
			(hide yes)
			(effects
				(font
					(size 1.27 1.27)
					(thickness 0.15)
				)
			)
		)
		(property "Description" "SMD Multilayer Ceramic Capacitor, 4.7 µF, 10 V, 0402 [1005 Metric], ± 20%, X5R, GRM Series"
			(at 0 0 270)
			(layer "F.Fab")
			(hide yes)
			(effects
				(font
					(size 1.27 1.27)
					(thickness 0.15)
				)
			)
		)
		(property "Author" "Antmicro"
			(at 9.4 236.33 0)
			(layer "B.Fab")
			(hide yes)
			(effects
				(font
					(size 1 1)
					(thickness 0.15)
				)
				(justify mirror)
			)
		)
		(property "Dielectric" ""
			(at 9.4 236.33 0)
			(layer "B.Fab")
			(hide yes)
			(effects
				(font
					(size 1 1)
					(thickness 0.15)
				)
				(justify mirror)
			)
		)
		(property "License" "Apache-2.0"
			(at 9.4 236.33 0)
			(layer "B.Fab")
			(hide yes)
			(effects
				(font
					(size 1 1)
					(thickness 0.15)
				)
				(justify mirror)
			)
		)
		(property "MPN" "GRM155R61A475MEAAD"
			(at 9.4 236.33 0)
			(layer "B.Fab")
			(hide yes)
			(effects
				(font
					(size 1 1)
					(thickness 0.15)
				)
				(justify mirror)
			)
		)
		(property "Manufacturer" "Murata"
			(at 9.4 236.33 0)
			(layer "B.Fab")
			(hide yes)
			(effects
				(font
					(size 1 1)
					(thickness 0.15)
				)
				(justify mirror)
			)
		)
		(property "Val" "4u7"
			(at 9.4 236.33 0)
			(layer "B.Fab")
			(hide yes)
			(effects
				(font
					(size 1 1)
					(thickness 0.15)
				)
				(justify mirror)
			)
		)
		(property "Voltage" ""
			(at 9.4 236.33 0)
			(layer "B.Fab")
			(hide yes)
			(effects
				(font
					(size 1 1)
					(thickness 0.15)
				)
				(justify mirror)
			)
		)
		(sheetname "/Interfaces/")
		(sheetfile "interfaces.kicad_sch")
		(attr smd)
		(fp_rect
			(start -0.925 0.47)
			(end 0.925 -0.47)
			(stroke
				(width 0.05)
				(type default)
			)
			(fill no)
			(layer "B.CrtYd")
		)
		(fp_line
			(start -0.494 0.25)
			(end 0.504 0.25)
			(stroke
				(width 0.15)
				(type solid)
			)
			(layer "B.Fab")
		)
		(fp_line
			(start 0.504 0.25)
			(end 0.504 -0.248)
			(stroke
				(width 0.15)
				(type solid)
			)
			(layer "B.Fab")
		)
		(fp_line
			(start -0.494 -0.248)
			(end -0.494 0.25)
			(stroke
				(width 0.15)
				(type solid)
			)
			(layer "B.Fab")
		)
		(fp_line
			(start 0.504 -0.248)
			(end -0.494 -0.248)
			(stroke
				(width 0.15)
				(type solid)
			)
			(layer "B.Fab")
		)
		(pad "1" smd roundrect
			(at -0.48 0 270)
			(size 0.59 0.64)
			(layers "B.Cu" "B.Mask" "B.Paste")
			(roundrect_rratio 0.25)
			(net 1 "GND")
			(pintype "passive")
		)
		(pad "2" smd roundrect
			(at 0.48 0 270)
			(size 0.59 0.64)
			(layers "B.Cu" "B.Mask" "B.Paste")
			(roundrect_rratio 0.25)
			(net 105 "Net-(C20-Pad2)")
			(pintype "passive")
		)
	)
	(footprint "antmicro-footprints:C_0402_1005Metric"
		(layer "B.Cu")
		(at 106.025 125.19 -90)
		(descr "Capacitor SMD 0402")
		(tags "capacitor SMD 0402")
		(property "Reference" "C130"
			(at 2.01 -0.375 90)
			(layer "B.SilkS")
			(effects
				(font
					(size 0.7 0.7)
					(thickness 0.15)
				)
				(justify left bottom mirror)
			)
		)
		(property "Value" "C_470n_0402"
			(at 0 -1.4 90)
			(layer "B.Fab")
			(effects
				(font
					(size 0.7 0.7)
					(thickness 0.15)
				)
				(justify left bottom mirror)
			)
		)
		(property "Datasheet" "https://product.tdk.com/en/search/capacitor/ceramic/mlcc/info?part_no=C1005X5R1E474M050BB"
			(at 0 0 270)
			(layer "F.Fab")
			(hide yes)
			(effects
				(font
					(size 1.27 1.27)
					(thickness 0.15)
				)
			)
		)
		(property "Description" "SMD Multilayer Ceramic Capacitor, 0.47 µF, 25 V, 0402 [1005 Metric], ± 20%, X5R, C"
			(at 0 0 270)
			(layer "F.Fab")
			(hide yes)
			(effects
				(font
					(size 1.27 1.27)
					(thickness 0.15)
				)
			)
		)
		(property "Author" "Antmicro"
			(at -19.165 231.215 0)
			(layer "B.Fab")
			(hide yes)
			(effects
				(font
					(size 1 1)
					(thickness 0.15)
				)
				(justify mirror)
			)
		)
		(property "Dielectric" ""
			(at -19.165 231.215 0)
			(layer "B.Fab")
			(hide yes)
			(effects
				(font
					(size 1 1)
					(thickness 0.15)
				)
				(justify mirror)
			)
		)
		(property "License" "Apache-2.0"
			(at -19.165 231.215 0)
			(layer "B.Fab")
			(hide yes)
			(effects
				(font
					(size 1 1)
					(thickness 0.15)
				)
				(justify mirror)
			)
		)
		(property "MPN" "C1005X5R1E474M050BB"
			(at -19.165 231.215 0)
			(layer "B.Fab")
			(hide yes)
			(effects
				(font
					(size 1 1)
					(thickness 0.15)
				)
				(justify mirror)
			)
		)
		(property "Manufacturer" "TDK"
			(at -19.165 231.215 0)
			(layer "B.Fab")
			(hide yes)
			(effects
				(font
					(size 1 1)
					(thickness 0.15)
				)
				(justify mirror)
			)
		)
		(property "Val" "470n"
			(at -19.165 231.215 0)
			(layer "B.Fab")
			(hide yes)
			(effects
				(font
					(size 1 1)
					(thickness 0.15)
				)
				(justify mirror)
			)
		)
		(property "Voltage" ""
			(at -19.165 231.215 0)
			(layer "B.Fab")
			(hide yes)
			(effects
				(font
					(size 1 1)
					(thickness 0.15)
				)
				(justify mirror)
			)
		)
		(property "DNP" ""
			(at 0 0 270)
			(unlocked yes)
			(layer "B.Fab")
			(hide yes)
			(effects
				(font
					(size 1 1)
					(thickness 0.15)
				)
				(justify mirror)
			)
		)
		(sheetname "/FPGA banks 13-16/")
		(sheetfile "fpga-banks-13-16.kicad_sch")
		(attr smd)
		(fp_rect
			(start -0.925 0.47)
			(end 0.925 -0.47)
			(stroke
				(width 0.05)
				(type default)
			)
			(fill no)
			(layer "B.CrtYd")
		)
		(fp_line
			(start -0.494 0.25)
			(end 0.504 0.25)
			(stroke
				(width 0.15)
				(type solid)
			)
			(layer "B.Fab")
		)
		(fp_line
			(start 0.504 0.25)
			(end 0.504 -0.248)
			(stroke
				(width 0.15)
				(type solid)
			)
			(layer "B.Fab")
		)
		(fp_line
			(start -0.494 -0.248)
			(end -0.494 0.25)
			(stroke
				(width 0.15)
				(type solid)
			)
			(layer "B.Fab")
		)
		(fp_line
			(start 0.504 -0.248)
			(end -0.494 -0.248)
			(stroke
				(width 0.15)
				(type solid)
			)
			(layer "B.Fab")
		)
		(pad "1" smd roundrect
			(at -0.48 0 270)
			(size 0.59 0.64)
			(layers "B.Cu" "B.Mask" "B.Paste")
			(roundrect_rratio 0.25)
			(net 1 "GND")
			(pintype "passive")
		)
		(pad "2" smd roundrect
			(at 0.48 0 270)
			(size 0.59 0.64)
			(layers "B.Cu" "B.Mask" "B.Paste")
			(roundrect_rratio 0.25)
			(net 2 "VCC3V3")
			(pintype "passive")
		)
	)
	(footprint "antmicro-footprints:R_0402_1005Metric"
		(layer "B.Cu")
		(at 107.275 123.225 90)
		(descr "Resistor SMD 0402")
		(tags "resistor SMD 0402")
		(property "Reference" "R85"
			(at -1.075 1.225 90)
			(layer "B.SilkS")
			(effects
				(font
					(size 0.7 0.7)
					(thickness 0.15)
				)
				(justify right bottom mirror)
			)
		)
		(property "Value" "R_4k7_0402"
			(at 0 -1.4 90)
			(layer "B.Fab")
			(effects
				(font
					(size 0.7 0.7)
					(thickness 0.15)
				)
				(justify right bottom mirror)
			)
		)
		(property "Datasheet" "https://www.bourns.com/docs/product-datasheets/cr.pdf"
			(at 0 0 90)
			(layer "F.Fab")
			(hide yes)
			(effects
				(font
					(size 1.27 1.27)
					(thickness 0.15)
				)
			)
		)
		(property "Description" "SMD Chip Resistor, 4.7 kohm, ± 1%, 62.5 mW, 0402 [1005 Metric], Thick Film, General Purpose"
			(at 0 0 90)
			(layer "F.Fab")
			(hide yes)
			(effects
				(font
					(size 1.27 1.27)
					(thickness 0.15)
				)
			)
		)
		(property "Author" "Antmicro"
			(at 230.5 15.95 0)
			(layer "B.Fab")
			(hide yes)
			(effects
				(font
					(size 1 1)
					(thickness 0.15)
				)
				(justify mirror)
			)
		)
		(property "License" "Apache-2.0"
			(at 230.5 15.95 0)
			(layer "B.Fab")
			(hide yes)
			(effects
				(font
					(size 1 1)
					(thickness 0.15)
				)
				(justify mirror)
			)
		)
		(property "MPN" "CR0402-FX-4701GLF"
			(at 230.5 15.95 0)
			(layer "B.Fab")
			(hide yes)
			(effects
				(font
					(size 1 1)
					(thickness 0.15)
				)
				(justify mirror)
			)
		)
		(property "Manufacturer" "Bourns"
			(at 230.5 15.95 0)
			(layer "B.Fab")
			(hide yes)
			(effects
				(font
					(size 1 1)
					(thickness 0.15)
				)
				(justify mirror)
			)
		)
		(property "Tolerance" "1%"
			(at 230.5 15.95 0)
			(layer "B.Fab")
			(hide yes)
			(effects
				(font
					(size 1 1)
					(thickness 0.15)
				)
				(justify mirror)
			)
		)
		(property "Val" "4k7"
			(at 230.5 15.95 0)
			(layer "B.Fab")
			(hide yes)
			(effects
				(font
					(size 1 1)
					(thickness 0.15)
				)
				(justify mirror)
			)
		)
		(sheetname "/FPGA banks 34-35 & CFG/")
		(sheetfile "fpga-banks-34-25-cfg.kicad_sch")
		(attr smd)
		(fp_rect
			(start -0.925 0.47)
			(end 0.925 -0.47)
			(stroke
				(width 0.05)
				(type default)
			)
			(fill no)
			(layer "B.CrtYd")
		)
		(fp_rect
			(start -0.5 0.25)
			(end 0.5 -0.25)
			(stroke
				(width 0.15)
				(type solid)
			)
			(fill no)
			(layer "B.Fab")
		)
		(pad "1" smd roundrect
			(at -0.48 0 90)
			(size 0.59 0.64)
			(layers "B.Cu" "B.Mask" "B.Paste")
			(roundrect_rratio 0.25)
			(net 2 "VCC3V3")
			(pintype "passive")
		)
		(pad "2" smd roundrect
			(at 0.48 0 90)
			(size 0.59 0.64)
			(layers "B.Cu" "B.Mask" "B.Paste")
			(roundrect_rratio 0.25)
			(net 342 "Net-(U14D-CFGBVS_0)")
			(pintype "passive")
		)
	)
	(footprint "antmicro-footprints:C_0402_1005Metric"
		(layer "B.Cu")
		(at 109.925 124.175 -90)
		(descr "Capacitor SMD 0402")
		(tags "capacitor SMD 0402")
		(property "Reference" "C119"
			(at -1.475 -1.375 90)
			(layer "B.SilkS")
			(effects
				(font
					(size 0.7 0.7)
					(thickness 0.15)
				)
				(justify left bottom mirror)
			)
		)
		(property "Value" "C_470n_0402"
			(at 0 -1.4 90)
			(layer "B.Fab")
			(effects
				(font
					(size 0.7 0.7)
					(thickness 0.15)
				)
				(justify left bottom mirror)
			)
		)
		(property "Datasheet" "https://product.tdk.com/en/search/capacitor/ceramic/mlcc/info?part_no=C1005X5R1E474M050BB"
			(at 0 0 270)
			(layer "F.Fab")
			(hide yes)
			(effects
				(font
					(size 1.27 1.27)
					(thickness 0.15)
				)
			)
		)
		(property "Description" "SMD Multilayer Ceramic Capacitor, 0.47 µF, 25 V, 0402 [1005 Metric], ± 20%, X5R, C"
			(at 0 0 270)
			(layer "F.Fab")
			(hide yes)
			(effects
				(font
					(size 1.27 1.27)
					(thickness 0.15)
				)
			)
		)
		(property "Author" "Antmicro"
			(at -14.25 234.1 0)
			(layer "B.Fab")
			(hide yes)
			(effects
				(font
					(size 1 1)
					(thickness 0.15)
				)
				(justify mirror)
			)
		)
		(property "Dielectric" ""
			(at -14.25 234.1 0)
			(layer "B.Fab")
			(hide yes)
			(effects
				(font
					(size 1 1)
					(thickness 0.15)
				)
				(justify mirror)
			)
		)
		(property "License" "Apache-2.0"
			(at -14.25 234.1 0)
			(layer "B.Fab")
			(hide yes)
			(effects
				(font
					(size 1 1)
					(thickness 0.15)
				)
				(justify mirror)
			)
		)
		(property "MPN" "C1005X5R1E474M050BB"
			(at -14.25 234.1 0)
			(layer "B.Fab")
			(hide yes)
			(effects
				(font
					(size 1 1)
					(thickness 0.15)
				)
				(justify mirror)
			)
		)
		(property "Manufacturer" "TDK"
			(at -14.25 234.1 0)
			(layer "B.Fab")
			(hide yes)
			(effects
				(font
					(size 1 1)
					(thickness 0.15)
				)
				(justify mirror)
			)
		)
		(property "Val" "470n"
			(at -14.25 234.1 0)
			(layer "B.Fab")
			(hide yes)
			(effects
				(font
					(size 1 1)
					(thickness 0.15)
				)
				(justify mirror)
			)
		)
		(property "Voltage" ""
			(at -14.25 234.1 0)
			(layer "B.Fab")
			(hide yes)
			(effects
				(font
					(size 1 1)
					(thickness 0.15)
				)
				(justify mirror)
			)
		)
		(sheetname "/FPGA banks 13-16/")
		(sheetfile "fpga-banks-13-16.kicad_sch")
		(attr smd)
		(fp_rect
			(start -0.925 0.47)
			(end 0.925 -0.47)
			(stroke
				(width 0.05)
				(type default)
			)
			(fill no)
			(layer "B.CrtYd")
		)
		(fp_line
			(start -0.494 0.25)
			(end 0.504 0.25)
			(stroke
				(width 0.15)
				(type solid)
			)
			(layer "B.Fab")
		)
		(fp_line
			(start 0.504 0.25)
			(end 0.504 -0.248)
			(stroke
				(width 0.15)
				(type solid)
			)
			(layer "B.Fab")
		)
		(fp_line
			(start -0.494 -0.248)
			(end -0.494 0.25)
			(stroke
				(width 0.15)
				(type solid)
			)
			(layer "B.Fab")
		)
		(fp_line
			(start 0.504 -0.248)
			(end -0.494 -0.248)
			(stroke
				(width 0.15)
				(type solid)
			)
			(layer "B.Fab")
		)
		(pad "1" smd roundrect
			(at -0.48 0 270)
			(size 0.59 0.64)
			(layers "B.Cu" "B.Mask" "B.Paste")
			(roundrect_rratio 0.25)
			(net 1 "GND")
			(pintype "passive")
		)
		(pad "2" smd roundrect
			(at 0.48 0 270)
			(size 0.59 0.64)
			(layers "B.Cu" "B.Mask" "B.Paste")
			(roundrect_rratio 0.25)
			(net 2 "VCC3V3")
			(pintype "passive")
		)
	)
	(footprint "antmicro-footprints:C_0402_1005Metric"
		(layer "B.Cu")
		(at 124.375 129.665 -90)
		(descr "Capacitor SMD 0402")
		(tags "capacitor SMD 0402")
		(property "Reference" "C248"
			(at 0.835 -0.385 90)
			(layer "B.SilkS")
			(effects
				(font
					(size 0.7 0.7)
					(thickness 0.15)
				)
				(justify left bottom mirror)
			)
		)
		(property "Value" "C_100n_0402"
			(at 0 -1.4 90)
			(layer "B.Fab")
			(effects
				(font
					(size 0.7 0.7)
					(thickness 0.15)
				)
				(justify left bottom mirror)
			)
		)
		(property "Datasheet" "https://www.murata.com/products/productdetail?partno=GRM155R61H104KE14%23"
			(at 0 0 270)
			(layer "F.Fab")
			(hide yes)
			(effects
				(font
					(size 1.27 1.27)
					(thickness 0.15)
				)
			)
		)
		(property "Description" "SMD Multilayer Ceramic Capacitor, 0.1 µF, 50 V, 0402 [1005 Metric], ± 10%, X5R, GRM Series"
			(at 0 0 270)
			(layer "F.Fab")
			(hide yes)
			(effects
				(font
					(size 1.27 1.27)
					(thickness 0.15)
				)
			)
		)
		(property "Author" "Antmicro"
			(at -5.29 254.04 0)
			(layer "B.Fab")
			(hide yes)
			(effects
				(font
					(size 1 1)
					(thickness 0.15)
				)
				(justify mirror)
			)
		)
		(property "Dielectric" "X5R"
			(at -5.29 254.04 0)
			(layer "B.Fab")
			(hide yes)
			(effects
				(font
					(size 1 1)
					(thickness 0.15)
				)
				(justify mirror)
			)
		)
		(property "License" "Apache-2.0"
			(at -5.29 254.04 0)
			(layer "B.Fab")
			(hide yes)
			(effects
				(font
					(size 1 1)
					(thickness 0.15)
				)
				(justify mirror)
			)
		)
		(property "MPN" "GRM155R61H104KE14D"
			(at -5.29 254.04 0)
			(layer "B.Fab")
			(hide yes)
			(effects
				(font
					(size 1 1)
					(thickness 0.15)
				)
				(justify mirror)
			)
		)
		(property "Manufacturer" "Murata"
			(at -5.29 254.04 0)
			(layer "B.Fab")
			(hide yes)
			(effects
				(font
					(size 1 1)
					(thickness 0.15)
				)
				(justify mirror)
			)
		)
		(property "Val" "100n"
			(at -5.29 254.04 0)
			(layer "B.Fab")
			(hide yes)
			(effects
				(font
					(size 1 1)
					(thickness 0.15)
				)
				(justify mirror)
			)
		)
		(property "Voltage" "50V"
			(at -5.29 254.04 0)
			(layer "B.Fab")
			(hide yes)
			(effects
				(font
					(size 1 1)
					(thickness 0.15)
				)
				(justify mirror)
			)
		)
		(sheetname "/Interfaces/")
		(sheetfile "interfaces.kicad_sch")
		(attr smd)
		(fp_rect
			(start -0.925 0.47)
			(end 0.925 -0.47)
			(stroke
				(width 0.05)
				(type default)
			)
			(fill no)
			(layer "B.CrtYd")
		)
		(fp_line
			(start -0.494 0.25)
			(end 0.504 0.25)
			(stroke
				(width 0.15)
				(type solid)
			)
			(layer "B.Fab")
		)
		(fp_line
			(start 0.504 0.25)
			(end 0.504 -0.248)
			(stroke
				(width 0.15)
				(type solid)
			)
			(layer "B.Fab")
		)
		(fp_line
			(start -0.494 -0.248)
			(end -0.494 0.25)
			(stroke
				(width 0.15)
				(type solid)
			)
			(layer "B.Fab")
		)
		(fp_line
			(start 0.504 -0.248)
			(end -0.494 -0.248)
			(stroke
				(width 0.15)
				(type solid)
			)
			(layer "B.Fab")
		)
		(pad "1" smd roundrect
			(at -0.48 0 270)
			(size 0.59 0.64)
			(layers "B.Cu" "B.Mask" "B.Paste")
			(roundrect_rratio 0.25)
			(net 1 "GND")
			(pintype "passive")
		)
		(pad "2" smd roundrect
			(at 0.48 0 270)
			(size 0.59 0.64)
			(layers "B.Cu" "B.Mask" "B.Paste")
			(roundrect_rratio 0.25)
			(net 108 "Net-(C177-Pad2)")
			(pintype "passive")
		)
	)
)
